# BASEBOARD_FAB2 (Tioga Pass) — schematic netlist excerpt (pin names and nets, part order shuffled) for the footprints in the layout excerpt that follows; sources: Cadence DE-HDL packaged netlist, KiCad conversion of Wiwynn_Tioga_Pass_MB.brd

J8F1  SKT-MINI67P-41-GP  pkg SOCKET-G4  page 185
  \1\  = GND
  \2\  = P3V3
  \3\  = GND
  \4\  = P3V3
  \5\  = P3E_PCH_M2_RX_DN<3>
  \6\  = NC_M2<0>
  \7\  = P3E_PCH_M2_RX_DP<3>
  \8\  = NC_M2<1>
  \9\  = GND
  \10\  = TP_LED_M2_ACT_N
  \11\  = P3E_PCH_M2_TX_C_DN<3>
  \12\  = P3V3
  \13\  = P3E_PCH_M2_TX_C_DP<3>
  \14\  = P3V3
  \15\  = GND
  \16\  = P3V3
  \17\  = P3E_PCH_M2_RX_DN<2>
  \18\  = P3V3
  \19\  = P3E_PCH_M2_RX_DP<2>
  \20\  = NC
  \21\  = GND
  \22\  = NC
  \23\  = P3E_PCH_M2_TX_C_DN<2>
  \24\  = NC
  \25\  = P3E_PCH_M2_TX_C_DP<2>
  \26\  = NC
  \27\  = GND
  \28\  = NC
  \29\  = P3E_PCH_M2_RX_DN<1>
  \30\  = NC
  \31\  = P3E_PCH_M2_RX_DP<1>
  \32\  = NC
  \33\  = GND
  \34\  = NC
  \35\  = P3E_PCH_M2_TX_C_DN<1>
  \36\  = NC
  \37\  = P3E_PCH_M2_TX_C_DP<1>
  \38\  = TP_M2_DEVSLP
  \39\  = GND
  \40\  = SMB_M2_SCL
  \41\  = P3E_PCH_M2_SATA6G_RX_R_DP
  \42\  = SMB_M2_SDA
  \43\  = P3E_PCH_M2_SATA6G_RX_R_DN
  \44\  = SMB_M2_ALT_N
  \45\  = GND
  \46\  = NC
  \47\  = P3E_PCH_M2_SATA6G_TX_R_DN
  \48\  = NC
  \49\  = P3E_PCH_M2_SATA6G_TX_R_DP
  \50\  = RST_PCIE_M2_DEV_IC_N
  \51\  = GND
  \52\  = PU_M2_CLK_REQ_N
  \53\  = CLK_100M_M2_DN
  \54\  = FM_PE_M2_WAKE_N
  \55\  = CLK_100M_M2_DP
  \56\  = NC
  \57\  = GND
  \58\  = NC
  \67\  = NC
  \68\  = TP_M2_32M_SUSCLK
  \69\  = FM_M2_SSD_PEDET
  \70\  = P3V3
  \71\  = GND
  \72\  = P3V3
  \73\  = GND
  \74\  = P3V3
  \75\  = GND
  \76\  = GND
  \77\  = GND
  NP1  = NC
  NP2  = NC

(kicad_pcb
	(version 20260206)
	(generator "pcbnew")
	(generator_version "10.0")
	(general
		(thickness 1.6)
		(legacy_teardrops no)
	)
	(paper "A4")
	(title_block
		(title "Wiwynn_Tioga_Pass_MB.brd")
		(comment 1 "Tioga Pass / footprint 894 of 4770 (J8F1), pads 47-71 of 71")
	)
	(layers
		(0 "F.Cu" signal "TOP")
		(4 "In1.Cu" signal "L2GND")
		(6 "In2.Cu" signal "L3")
		(8 "In3.Cu" signal "L4GND")
		(10 "In4.Cu" signal "L5")
		(12 "In5.Cu" signal "L6GND")
		(14 "In6.Cu" signal "L7VCC")
		(16 "In7.Cu" signal "L8VCC")
		(18 "In8.Cu" signal "L9GND")
		(20 "In9.Cu" signal "L10")
		(22 "In10.Cu" signal "L11GND")
		(24 "In11.Cu" signal "L12")
		(26 "In12.Cu" signal "L13GND")
		(2 "B.Cu" signal "BOTTOM")
		(9 "F.Adhes" user "F.Adhesive")
		(11 "B.Adhes" user "B.Adhesive")
		(13 "F.Paste" user "Package Geometry/Pastemask Top")
		(15 "B.Paste" user "Package Geometry/Pastemask Bottom")
		(5 "F.SilkS" user "Ref Des/Silkscreen Top")
		(7 "B.SilkS" user "Ref Des/Silkscreen Bottom")
		(1 "F.Mask" user "Board Geometry/Soldermask Top")
		(3 "B.Mask" user "Board Geometry/Soldermask Bottom")
		(17 "Dwgs.User" user "User.Drawings")
		(19 "Cmts.User" user "User.Comments")
		(21 "Eco1.User" user "User.Eco1")
		(23 "Eco2.User" user "User.Eco2")
		(25 "Edge.Cuts" user "Board Geometry/Outline")
		(27 "Margin" user)
		(31 "F.CrtYd" user "Package Geometry/Place Bound Top")
		(29 "B.CrtYd" user "Package Geometry/Place Bound Bottom")
		(35 "F.Fab" user "Ref Des/Assembly Top")
		(33 "B.Fab" user "Ref Des/Assembly Bottom")
	)
	(footprint ""
		(layer "F.Cu")
		(at 388.072376 -30.520894 90)
		(property "Reference" "J8F1"
			(at 0 0 90)
			(layer "F.SilkS")
			(hide yes)
			(effects
				(font
					(size 1.27 1.27)
				)
			)
		)
		(property "Value" "*"
			(at 12.319 -1.3335 90)
			(unlocked yes)
			(layer "F.Fab")
			(hide yes)
			(effects
				(font
					(size 1.27 1.016)
					(thickness 0.1524)
				)
			)
		)
		(property "Device Type" "SKT-MINI67P-41-GP_SOCKET-G4-SKA"
			(at 12.319 -2.8575 90)
			(unlocked yes)
			(layer "F.Fab")
			(hide yes)
			(effects
				(font
					(size 1.27 1.016)
					(thickness 0.1524)
				)
			)
		)
		(duplicate_pad_numbers_are_jumpers no)
		(pad "45" smd rect
			(at 1.75006 -5.275072 90)
			(size 0.3048 1.5494)
			(layers "F.Cu" "F.Mask" "F.Paste")
			(net "GND")
		)
		(pad "46" smd rect
			(at 1.999996 2.275078 90)
			(size 0.3048 1.5494)
			(layers "F.Cu" "F.Mask" "F.Paste")
			(net "Net_326")
		)
		(pad "47" smd rect
			(at 2.249932 -5.275072 90)
			(size 0.3048 1.5494)
			(layers "F.Cu" "F.Mask" "F.Paste")
			(net "P3E_PCH_M2_SATA6G_TX_R_DN")
		)
		(pad "48" smd rect
			(at 2.500122 2.275078 90)
			(size 0.3048 1.5494)
			(layers "F.Cu" "F.Mask" "F.Paste")
			(net "Net_327")
		)
		(pad "49" smd rect
			(at 2.750058 -5.275072 90)
			(size 0.3048 1.5494)
			(layers "F.Cu" "F.Mask" "F.Paste")
			(net "P3E_PCH_M2_SATA6G_TX_R_DP")
		)
		(pad "50" smd rect
			(at 2.999994 2.275078 90)
			(size 0.3048 1.5494)
			(layers "F.Cu" "F.Mask" "F.Paste")
			(net "RST_PCIE_M2_DEV_IC_N")
		)
		(pad "51" smd rect
			(at 3.24993 -5.275072 90)
			(size 0.3048 1.5494)
			(layers "F.Cu" "F.Mask" "F.Paste")
			(net "GND")
		)
		(pad "52" smd rect
			(at 3.50012 2.275078 90)
			(size 0.3048 1.5494)
			(layers "F.Cu" "F.Mask" "F.Paste")
			(net "PU_M2_CLK_REQ_N")
		)
		(pad "53" smd rect
			(at 3.750056 -5.275072 90)
			(size 0.3048 1.5494)
			(layers "F.Cu" "F.Mask" "F.Paste")
			(net "CLK_100M_M2_DN")
		)
		(pad "54" smd rect
			(at 3.999992 2.275078 90)
			(size 0.3048 1.5494)
			(layers "F.Cu" "F.Mask" "F.Paste")
			(net "FM_PE_M2_WAKE_N")
		)
		(pad "55" smd rect
			(at 4.249928 -5.275072 90)
			(size 0.3048 1.5494)
			(layers "F.Cu" "F.Mask" "F.Paste")
			(net "CLK_100M_M2_DP")
		)
		(pad "56" smd rect
			(at 4.500118 2.275078 90)
			(size 0.3048 1.5494)
			(layers "F.Cu" "F.Mask" "F.Paste")
			(net "Net_328")
		)
		(pad "57" smd rect
			(at 4.750054 -5.275072 90)
			(size 0.3048 1.5494)
			(layers "F.Cu" "F.Mask" "F.Paste")
			(net "GND")
		)
		(pad "58" smd rect
			(at 4.99999 2.275078 90)
			(size 0.3048 1.5494)
			(layers "F.Cu" "F.Mask" "F.Paste")
			(net "Net_329")
		)
		(pad "67" smd rect
			(at 7.249922 -5.275072 90)
			(size 0.3048 1.5494)
			(layers "F.Cu" "F.Mask" "F.Paste")
			(net "Net_330")
		)
		(pad "68" smd rect
			(at 7.500112 2.275078 90)
			(size 0.3048 1.5494)
			(layers "F.Cu" "F.Mask" "F.Paste")
			(net "TP_M2_32M_SUSCLK")
		)
		(pad "69" smd rect
			(at 7.750048 -5.275072 90)
			(size 0.3048 1.5494)
			(layers "F.Cu" "F.Mask" "F.Paste")
			(net "FM_M2_SSD_PEDET")
		)
		(pad "70" smd rect
			(at 7.999984 2.275078 90)
			(size 0.3048 1.5494)
			(layers "F.Cu" "F.Mask" "F.Paste")
			(net "P3V3")
		)
		(pad "71" smd rect
			(at 8.24992 -5.275072 90)
			(size 0.3048 1.5494)
			(layers "F.Cu" "F.Mask" "F.Paste")
			(net "GND")
		)
		(pad "72" smd rect
			(at 8.50011 2.275078 90)
			(size 0.3048 1.5494)
			(layers "F.Cu" "F.Mask" "F.Paste")
			(net "P3V3")
		)
		(pad "73" smd rect
			(at 8.750046 -5.275072 90)
			(size 0.3048 1.5494)
			(layers "F.Cu" "F.Mask" "F.Paste")
			(net "GND")
		)
		(pad "74" smd rect
			(at 8.999982 2.275078 90)
			(size 0.3048 1.5494)
			(layers "F.Cu" "F.Mask" "F.Paste")
			(net "P3V3")
		)
		(pad "75" smd rect
			(at 9.249918 -5.275072 90)
			(size 0.3048 1.5494)
			(layers "F.Cu" "F.Mask" "F.Paste")
			(net "GND")
		)
		(pad "76" smd rect
			(at -10.349992 -4.500118 90)
			(size 1.1938 2.7432)
			(layers "F.Cu" "F.Mask" "F.Paste")
			(net "GND")
		)
		(pad "77" smd rect
			(at 10.349992 -4.500118 90)
			(size 1.1938 2.7432)
			(layers "F.Cu" "F.Mask" "F.Paste")
			(net "GND")
		)
	)
)
